(kicad_pcb
	(version 20221018)
	(generator pcbnew)
	(general
    (thickness 1.656)
  )
	(paper "A4")
	(title_block
    (title "SDI-MIPI Bridge")
    (date "2023-08-09")
    (rev "1.3.4")
    (company "Antmicro")
		(comment 9 "footprints 13-17 of 190")
	)
	(layers
    (0 "F.Cu" signal)
    (1 "In1.Cu" power)
    (2 "In2.Cu" power)
    (3 "In3.Cu" signal)
    (4 "In4.Cu" signal)
    (31 "B.Cu" signal)
    (32 "B.Adhes" user "B.Adhesive")
    (33 "F.Adhes" user "F.Adhesive")
    (34 "B.Paste" user)
    (35 "F.Paste" user)
    (36 "B.SilkS" user "B.Silkscreen")
    (37 "F.SilkS" user "F.Silkscreen")
    (38 "B.Mask" user)
    (39 "F.Mask" user)
    (40 "Dwgs.User" user "User.Drawings")
    (41 "Cmts.User" user "User.Comments")
    (42 "Eco1.User" user "User.Eco1")
    (43 "Eco2.User" user "User.Eco2")
    (44 "Edge.Cuts" user)
    (45 "Margin" user)
    (46 "B.CrtYd" user "B.Courtyard")
    (47 "F.CrtYd" user "F.Courtyard")
    (48 "B.Fab" user)
    (49 "F.Fab" user)
  )
	(footprint "sdi-mipi-bridge-footprints:R_0402_1005Metric" (layer "F.Cu")
    (at 130 107.4 90)
    (descr "Resistor SMD 0402")
    (tags "resistor SMD 0402")
    (property "Author" "Antmicro")
    (property "Current" "1A")
    (property "License" "Apache-2.0")
    (property "MPN" "ERJ2GE0R00X")
    (property "Manufacturer" "Panasonic")
    (property "Sheetfile" "sdi-mipi-bridge.kicad_sch")
    (property "Sheetname" "")
    (property "Tolerance" "")
    (property "Val" "0R")
    (property "ki_description" "0R resistor in 0402 package with unspecified tolerance")
    (attr smd)
    (fp_text reference "R31" (at -0.9 3.3 90) (layer "F.SilkS")
        (effects (font (size 0.65 0.65) (thickness 0.15)) (justify left bottom))
    )
    (fp_text value "R_0R_0402" (at 0 1.4 90) (layer "F.Fab") hide
        (effects (font (size 0.7 0.7) (thickness 0.15)) (justify left bottom))
    )
    (fp_text user "Author: Antmicro" (at -0.95 4.169 90) (layer "F.Fab") hide
        (effects (font (size 0.7 0.7) (thickness 0.15)) (justify left bottom))
    )
    (fp_text user "License: Apache-2.0" (at -0.95 5.169 90) (layer "F.Fab") hide
        (effects (font (size 0.7 0.7) (thickness 0.15)) (justify left bottom))
    )
    (fp_text user "${REFERENCE}" (at -0.95 3.168 90) (layer "F.Fab") hide
        (effects (font (size 0.7 0.7) (thickness 0.15)) (justify left bottom))
    )
    (fp_rect (start -0.93 -0.47) (end 0.93 0.47)
      (stroke (width 0.05) (type solid)) (fill none) (layer "F.CrtYd"))
    (fp_rect (start -0.5 -0.25) (end 0.5 0.25)
      (stroke (width 0.15) (type solid)) (fill none) (layer "F.Fab"))
    (pad "1" smd roundrect (at -0.485 0 90) (size 0.59 0.64) (layers "F.Cu" "F.Paste" "F.Mask") (roundrect_rratio 0.25)
      (net 20 "/LOCKED") (pintype "passive"))
    (pad "2" smd roundrect (at 0.485 0 90) (size 0.59 0.64) (layers "F.Cu" "F.Paste" "F.Mask") (roundrect_rratio 0.25)
      (net 87 "/LOCKED_CL") (pintype "passive"))
  )
	(footprint "sdi-mipi-bridge-footprints:WE_68715014522_ONE-SIDE" (layer "F.Cu")
    (at 164.6 116.7 90)
    (property "Author" "Antmicro")
    (property "License" "Apache-2.0")
    (property "MPN" "68715014522")
    (property "Manufacturer" "Würth Elektronik")
    (property "Sheetfile" "sdi-mipi-bridge.kicad_sch")
    (property "Sheetname" "")
    (attr smd)
    (fp_text reference "J3" (at 0 -3.4 90) (layer "F.SilkS")
        (effects (font (size 0.65 0.65) (thickness 0.15)) (justify left bottom))
    )
    (fp_text value "Conn_FFC_68715014522_ONE-SIDE" (at 0 4.499 90) (layer "F.Fab") hide
        (effects (font (size 0.7 0.7) (thickness 0.15)) (justify left bottom))
    )
    (fp_text user "${REFERENCE}" (at -16.2 8.9 90) (layer "F.Fab")
        (effects (font (size 0.7 0.7) (thickness 0.15)) (justify left bottom))
    )
    (fp_text user "Author: Antmicro" (at -16.2 6.499 90) (layer "F.Fab")
        (effects (font (size 0.7 0.7) (thickness 0.15)) (justify left bottom))
    )
    (fp_text user "License: Apache-2.0" (at -16.2 7.7 90) (layer "F.Fab")
        (effects (font (size 0.7 0.7) (thickness 0.15)) (justify left bottom))
    )
    (fp_line (start -15.85 -2.15) (end -12.5 -2.15)
      (stroke (width 0.15) (type solid)) (layer "F.SilkS"))
    (fp_line (start -15.85 2.7) (end -15.85 -2.15)
      (stroke (width 0.15) (type solid)) (layer "F.SilkS"))
    (fp_line (start -12.5 -2.976) (end 12.499 -2.976)
      (stroke (width 0.15) (type solid)) (layer "F.SilkS"))
    (fp_line (start -12.5 -2.15) (end -12.5 -2.976)
      (stroke (width 0.15) (type solid)) (layer "F.SilkS"))
    (fp_line (start 12.499 -2.15) (end 12.499 -2.976)
      (stroke (width 0.15) (type solid)) (layer "F.SilkS"))
    (fp_line (start 15.849 -2.15) (end 12.499 -2.15)
      (stroke (width 0.15) (type solid)) (layer "F.SilkS"))
    (fp_line (start 15.849 2.7) (end -15.85 2.7)
      (stroke (width 0.15) (type solid)) (layer "F.SilkS"))
    (fp_line (start 15.849 2.7) (end 15.849 -2.15)
      (stroke (width 0.15) (type solid)) (layer "F.SilkS"))
    (fp_circle (center -12.901 -2.9) (end -12.85 -2.851)
      (stroke (width 0.15) (type solid)) (fill solid) (layer "F.SilkS"))
    (fp_rect (start -16.2 -3.25) (end 16.19 3.55)
      (stroke (width 0.05) (type solid)) (fill none) (layer "F.CrtYd"))
    (pad "1" smd roundrect (at -12.25 -2.15 90) (size 0.3 1.2) (layers "F.Cu" "F.Paste" "F.Mask") (roundrect_rratio 0.25)
      (net 143 "/MIPI0_D3_N") (pintype "passive"))
    (pad "2" smd roundrect (at -11.75 -2.15 90) (size 0.3 1.2) (layers "F.Cu" "F.Paste" "F.Mask") (roundrect_rratio 0.25)
      (net 144 "/MIPI0_D3_P") (pintype "passive"))
    (pad "3" smd roundrect (at -11.25 -2.15 90) (size 0.3 1.2) (layers "F.Cu" "F.Paste" "F.Mask") (roundrect_rratio 0.25)
      (net 145 "/MIPI0_D2_N") (pintype "passive"))
    (pad "4" smd roundrect (at -10.75 -2.15 90) (size 0.3 1.2) (layers "F.Cu" "F.Paste" "F.Mask") (roundrect_rratio 0.25)
      (net 146 "/MIPI0_D2_P") (pintype "passive"))
    (pad "5" smd roundrect (at -10.25 -2.15 90) (size 0.3 1.2) (layers "F.Cu" "F.Paste" "F.Mask") (roundrect_rratio 0.25)
      (net 147 "/MIPI0_D1_N") (pintype "passive"))
    (pad "6" smd roundrect (at -9.75 -2.15 90) (size 0.3 1.2) (layers "F.Cu" "F.Paste" "F.Mask") (roundrect_rratio 0.25)
      (net 148 "/MIPI0_D1_P") (pintype "passive"))
    (pad "7" smd roundrect (at -9.25 -2.15 90) (size 0.3 1.2) (layers "F.Cu" "F.Paste" "F.Mask") (roundrect_rratio 0.25)
      (net 149 "/MIPI0_D0_N") (pintype "passive"))
    (pad "8" smd roundrect (at -8.75 -2.15 90) (size 0.3 1.2) (layers "F.Cu" "F.Paste" "F.Mask") (roundrect_rratio 0.25)
      (net 150 "/MIPI0_D0_P") (pintype "passive"))
    (pad "9" smd roundrect (at -8.25 -2.15 90) (size 0.3 1.2) (layers "F.Cu" "F.Paste" "F.Mask") (roundrect_rratio 0.25)
      (net 1 "GNDREF") (pintype "passive"))
    (pad "10" smd roundrect (at -7.75 -2.15 90) (size 0.3 1.2) (layers "F.Cu" "F.Paste" "F.Mask") (roundrect_rratio 0.25)
      (net 151 "/MIPI0_CLK_N") (pintype "passive"))
    (pad "11" smd roundrect (at -7.25 -2.15 90) (size 0.3 1.2) (layers "F.Cu" "F.Paste" "F.Mask") (roundrect_rratio 0.25)
      (net 152 "/MIPI0_CLK_P") (pintype "passive"))
    (pad "12" smd roundrect (at -6.75 -2.15 90) (size 0.3 1.2) (layers "F.Cu" "F.Paste" "F.Mask") (roundrect_rratio 0.25)
      (net 1 "GNDREF") (pintype "passive"))
    (pad "13" smd roundrect (at -6.25 -2.15 90) (size 0.3 1.2) (layers "F.Cu" "F.Paste" "F.Mask") (roundrect_rratio 0.25)
      (net 48 "unconnected-(J3-Pad13)") (pintype "passive+no_connect"))
    (pad "14" smd roundrect (at -5.75 -2.15 90) (size 0.3 1.2) (layers "F.Cu" "F.Paste" "F.Mask") (roundrect_rratio 0.25)
      (net 107 "unconnected-(J3-Pad14)") (pintype "passive+no_connect"))
    (pad "15" smd roundrect (at -5.25 -2.15 90) (size 0.3 1.2) (layers "F.Cu" "F.Paste" "F.Mask") (roundrect_rratio 0.25)
      (net 1 "GNDREF") (pintype "passive"))
    (pad "16" smd roundrect (at -4.75 -2.15 90) (size 0.3 1.2) (layers "F.Cu" "F.Paste" "F.Mask") (roundrect_rratio 0.25)
      (net 108 "unconnected-(J3-Pad16)") (pintype "passive+no_connect"))
    (pad "17" smd roundrect (at -4.25 -2.15 90) (size 0.3 1.2) (layers "F.Cu" "F.Paste" "F.Mask") (roundrect_rratio 0.25)
      (net 109 "unconnected-(J3-Pad17)") (pintype "passive+no_connect"))
    (pad "18" smd roundrect (at -3.75 -2.15 90) (size 0.3 1.2) (layers "F.Cu" "F.Paste" "F.Mask") (roundrect_rratio 0.25)
      (net 1 "GNDREF") (pintype "passive"))
    (pad "19" smd roundrect (at -3.25 -2.15 90) (size 0.3 1.2) (layers "F.Cu" "F.Paste" "F.Mask") (roundrect_rratio 0.25)
      (net 153 "/MIPI1_D3_N") (pintype "passive"))
    (pad "20" smd roundrect (at -2.75 -2.15 90) (size 0.3 1.2) (layers "F.Cu" "F.Paste" "F.Mask") (roundrect_rratio 0.25)
      (net 154 "/MIPI1_D3_P") (pintype "passive"))
    (pad "21" smd roundrect (at -2.25 -2.15 90) (size 0.3 1.2) (layers "F.Cu" "F.Paste" "F.Mask") (roundrect_rratio 0.25)
      (net 155 "/MIPI1_D2_N") (pintype "passive"))
    (pad "22" smd roundrect (at -1.75 -2.15 90) (size 0.3 1.2) (layers "F.Cu" "F.Paste" "F.Mask") (roundrect_rratio 0.25)
      (net 156 "/MIPI1_D2_P") (pintype "passive"))
    (pad "23" smd roundrect (at -1.25 -2.15 90) (size 0.3 1.2) (layers "F.Cu" "F.Paste" "F.Mask") (roundrect_rratio 0.25)
      (net 157 "/MIPI1_D1_N") (pintype "passive"))
    (pad "24" smd roundrect (at -0.75 -2.15 90) (size 0.3 1.2) (layers "F.Cu" "F.Paste" "F.Mask") (roundrect_rratio 0.25)
      (net 158 "/MIPI1_D1_P") (pintype "passive"))
    (pad "25" smd roundrect (at -0.25 -2.15 90) (size 0.3 1.2) (layers "F.Cu" "F.Paste" "F.Mask") (roundrect_rratio 0.25)
      (net 159 "/MIPI1_D0_N") (pintype "passive"))
    (pad "26" smd roundrect (at 0.247 -2.15 90) (size 0.3 1.2) (layers "F.Cu" "F.Paste" "F.Mask") (roundrect_rratio 0.25)
      (net 160 "/MIPI1_D0_P") (pintype "passive"))
    (pad "27" smd roundrect (at 0.747 -2.15 90) (size 0.3 1.2) (layers "F.Cu" "F.Paste" "F.Mask") (roundrect_rratio 0.25)
      (net 1 "GNDREF") (pintype "passive"))
    (pad "28" smd roundrect (at 1.249 -2.15 90) (size 0.3 1.2) (layers "F.Cu" "F.Paste" "F.Mask") (roundrect_rratio 0.25)
      (net 161 "/MIPI1_CLK_N") (pintype "passive"))
    (pad "29" smd roundrect (at 1.749 -2.15 90) (size 0.3 1.2) (layers "F.Cu" "F.Paste" "F.Mask") (roundrect_rratio 0.25)
      (net 162 "/MIPI1_CLK_P") (pintype "passive"))
    (pad "30" smd roundrect (at 2.249 -2.15 90) (size 0.3 1.2) (layers "F.Cu" "F.Paste" "F.Mask") (roundrect_rratio 0.25)
      (net 1 "GNDREF") (pintype "passive"))
    (pad "31" smd roundrect (at 2.749 -2.15 90) (size 0.3 1.2) (layers "F.Cu" "F.Paste" "F.Mask") (roundrect_rratio 0.25)
      (net 110 "unconnected-(J3-Pad31)") (pintype "passive+no_connect"))
    (pad "32" smd roundrect (at 3.249 -2.15 90) (size 0.3 1.2) (layers "F.Cu" "F.Paste" "F.Mask") (roundrect_rratio 0.25)
      (net 111 "unconnected-(J3-Pad32)") (pintype "passive+no_connect"))
    (pad "33" smd roundrect (at 3.749 -2.15 90) (size 0.3 1.2) (layers "F.Cu" "F.Paste" "F.Mask") (roundrect_rratio 0.25)
      (net 113 "/RST") (pintype "passive+no_connect"))
    (pad "34" smd roundrect (at 4.248 -2.15 90) (size 0.3 1.2) (layers "F.Cu" "F.Paste" "F.Mask") (roundrect_rratio 0.25)
      (net 112 "unconnected-(J3-Pad34)") (pintype "passive+no_connect"))
    (pad "35" smd roundrect (at 4.748 -2.15 90) (size 0.3 1.2) (layers "F.Cu" "F.Paste" "F.Mask") (roundrect_rratio 0.25)
      (net 114 "unconnected-(J3-Pad35)") (pintype "passive+no_connect"))
    (pad "36" smd roundrect (at 5.248 -2.15 90) (size 0.3 1.2) (layers "F.Cu" "F.Paste" "F.Mask") (roundrect_rratio 0.25)
      (net 115 "unconnected-(J3-Pad36)") (pintype "passive+no_connect"))
    (pad "37" smd roundrect (at 5.749 -2.15 90) (size 0.3 1.2) (layers "F.Cu" "F.Paste" "F.Mask") (roundrect_rratio 0.25)
      (net 116 "unconnected-(J3-Pad37)") (pintype "passive+no_connect"))
    (pad "38" smd roundrect (at 6.249 -2.15 90) (size 0.3 1.2) (layers "F.Cu" "F.Paste" "F.Mask") (roundrect_rratio 0.25)
      (net 117 "unconnected-(J3-Pad38)") (pintype "passive+no_connect"))
    (pad "39" smd roundrect (at 6.749 -2.15 90) (size 0.3 1.2) (layers "F.Cu" "F.Paste" "F.Mask") (roundrect_rratio 0.25)
      (net 83 "/SDA1") (pintype "passive"))
    (pad "40" smd roundrect (at 7.249 -2.15 90) (size 0.3 1.2) (layers "F.Cu" "F.Paste" "F.Mask") (roundrect_rratio 0.25)
      (net 82 "/SCL1") (pintype "passive"))
    (pad "41" smd roundrect (at 7.749 -2.15 90) (size 0.3 1.2) (layers "F.Cu" "F.Paste" "F.Mask") (roundrect_rratio 0.25)
      (net 81 "/SDA2") (pintype "passive"))
    (pad "42" smd roundrect (at 8.249 -2.15 90) (size 0.3 1.2) (layers "F.Cu" "F.Paste" "F.Mask") (roundrect_rratio 0.25)
      (net 80 "/SCL2") (pintype "passive"))
    (pad "43" smd roundrect (at 8.749 -2.15 90) (size 0.3 1.2) (layers "F.Cu" "F.Paste" "F.Mask") (roundrect_rratio 0.25)
      (net 118 "unconnected-(J3-Pad43)") (pintype "passive+no_connect"))
    (pad "44" smd roundrect (at 9.249 -2.15 90) (size 0.3 1.2) (layers "F.Cu" "F.Paste" "F.Mask") (roundrect_rratio 0.25)
      (net 119 "unconnected-(J3-Pad44)") (pintype "passive+no_connect"))
    (pad "45" smd roundrect (at 9.749 -2.15 90) (size 0.3 1.2) (layers "F.Cu" "F.Paste" "F.Mask") (roundrect_rratio 0.25)
      (net 120 "unconnected-(J3-Pad45)") (pintype "passive+no_connect"))
    (pad "46" smd roundrect (at 10.249 -2.15 90) (size 0.3 1.2) (layers "F.Cu" "F.Paste" "F.Mask") (roundrect_rratio 0.25)
      (net 121 "unconnected-(J3-Pad46)") (pintype "passive+no_connect"))
    (pad "47" smd roundrect (at 10.749 -2.15 90) (size 0.3 1.2) (layers "F.Cu" "F.Paste" "F.Mask") (roundrect_rratio 0.25)
      (net 136 "Net-(J3-Pad47)") (pintype "passive"))
    (pad "48" smd roundrect (at 11.249 -2.15 90) (size 0.3 1.2) (layers "F.Cu" "F.Paste" "F.Mask") (roundrect_rratio 0.25)
      (net 136 "Net-(J3-Pad47)") (pintype "passive"))
    (pad "49" smd roundrect (at 11.749 -2.15 90) (size 0.3 1.2) (layers "F.Cu" "F.Paste" "F.Mask") (roundrect_rratio 0.25)
      (net 122 "unconnected-(J3-Pad49)") (pintype "passive+no_connect"))
    (pad "50" smd roundrect (at 12.249 -2.15 90) (size 0.3 1.2) (layers "F.Cu" "F.Paste" "F.Mask") (roundrect_rratio 0.25)
      (net 123 "unconnected-(J3-Pad50)") (pintype "passive+no_connect"))
    (pad "SH" smd roundrect (at -14.199 -0.3 90) (size 2.7 3) (layers "F.Cu" "F.Paste" "F.Mask") (roundrect_rratio 0.05)
      (net 1 "GNDREF") (pintype "passive"))
    (pad "SH" smd roundrect (at 14.198 -0.3 90) (size 2.7 3) (layers "F.Cu" "F.Paste" "F.Mask") (roundrect_rratio 0.05)
      (net 1 "GNDREF") (pintype "passive"))
  )
	(footprint "sdi-mipi-bridge-footprints:R_0402_1005Metric" (layer "F.Cu")
    (at 156.945 111.3 180)
    (descr "Resistor SMD 0402")
    (tags "resistor SMD 0402")
    (property "Author" "Antmicro")
    (property "Current" "1A")
    (property "License" "Apache-2.0")
    (property "MPN" "ERJ2GE0R00X")
    (property "Manufacturer" "Panasonic")
    (property "Sheetfile" "sdi-mipi-bridge.kicad_sch")
    (property "Sheetname" "")
    (property "Tolerance" "")
    (property "Val" "0R")
    (property "ki_description" "0R resistor in 0402 package with unspecified tolerance")
    (attr smd)
    (fp_text reference "R38" (at -2.955 -0.4) (layer "F.SilkS")
        (effects (font (size 0.65 0.65) (thickness 0.15)) (justify right bottom))
    )
    (fp_text value "R_0R_0402" (at 0 1.4) (layer "F.Fab") hide
        (effects (font (size 0.7 0.7) (thickness 0.15)) (justify right bottom))
    )
    (fp_text user "License: Apache-2.0" (at -0.95 5.169) (layer "F.Fab") hide
        (effects (font (size 0.7 0.7) (thickness 0.15)) (justify right bottom))
    )
    (fp_text user "Author: Antmicro" (at -0.95 4.169) (layer "F.Fab") hide
        (effects (font (size 0.7 0.7) (thickness 0.15)) (justify right bottom))
    )
    (fp_text user "${REFERENCE}" (at -0.95 3.168) (layer "F.Fab") hide
        (effects (font (size 0.7 0.7) (thickness 0.15)) (justify right bottom))
    )
    (fp_rect (start -0.93 -0.47) (end 0.93 0.47)
      (stroke (width 0.05) (type solid)) (fill none) (layer "F.CrtYd"))
    (fp_rect (start -0.5 -0.25) (end 0.5 0.25)
      (stroke (width 0.15) (type solid)) (fill none) (layer "F.Fab"))
    (pad "1" smd roundrect (at -0.485 0 180) (size 0.59 0.64) (layers "F.Cu" "F.Paste" "F.Mask") (roundrect_rratio 0.25)
      (net 82 "/SCL1") (pintype "passive"))
    (pad "2" smd roundrect (at 0.485 0 180) (size 0.59 0.64) (layers "F.Cu" "F.Paste" "F.Mask") (roundrect_rratio 0.25)
      (net 99 "/SPI_SS(SCL)") (pintype "passive"))
  )
	(footprint "sdi-mipi-bridge-footprints:R_0402_1005Metric" (layer "F.Cu")
    (at 156.945 110.1 180)
    (descr "Resistor SMD 0402")
    (tags "resistor SMD 0402")
    (property "Author" "Antmicro")
    (property "Current" "1A")
    (property "License" "Apache-2.0")
    (property "MPN" "ERJ2GE0R00X")
    (property "Manufacturer" "Panasonic")
    (property "Sheetfile" "sdi-mipi-bridge.kicad_sch")
    (property "Sheetname" "")
    (property "Tolerance" "")
    (property "Val" "0R")
    (property "ki_description" "0R resistor in 0402 package with unspecified tolerance")
    (attr smd)
    (fp_text reference "R40" (at -2.955 -0.4) (layer "F.SilkS")
        (effects (font (size 0.65 0.65) (thickness 0.15)) (justify right bottom))
    )
    (fp_text value "R_0R_0402" (at 0 1.4) (layer "F.Fab") hide
        (effects (font (size 0.7 0.7) (thickness 0.15)) (justify right bottom))
    )
    (fp_text user "${REFERENCE}" (at -0.95 3.168) (layer "F.Fab") hide
        (effects (font (size 0.7 0.7) (thickness 0.15)) (justify right bottom))
    )
    (fp_text user "License: Apache-2.0" (at -0.95 5.169) (layer "F.Fab") hide
        (effects (font (size 0.7 0.7) (thickness 0.15)) (justify right bottom))
    )
    (fp_text user "Author: Antmicro" (at -0.95 4.169) (layer "F.Fab") hide
        (effects (font (size 0.7 0.7) (thickness 0.15)) (justify right bottom))
    )
    (fp_rect (start -0.93 -0.47) (end 0.93 0.47)
      (stroke (width 0.05) (type solid)) (fill none) (layer "F.CrtYd"))
    (fp_rect (start -0.5 -0.25) (end 0.5 0.25)
      (stroke (width 0.15) (type solid)) (fill none) (layer "F.Fab"))
    (pad "1" smd roundrect (at -0.485 0 180) (size 0.59 0.64) (layers "F.Cu" "F.Paste" "F.Mask") (roundrect_rratio 0.25)
      (net 82 "/SCL1") (pintype "passive"))
    (pad "2" smd roundrect (at 0.485 0 180) (size 0.59 0.64) (layers "F.Cu" "F.Paste" "F.Mask") (roundrect_rratio 0.25)
      (net 61 "/SCL_GS") (pintype "passive"))
  )
	(footprint "sdi-mipi-bridge-footprints:R_0402_1005Metric" (layer "F.Cu")
    (at 156.945 107.7 180)
    (descr "Resistor SMD 0402")
    (tags "resistor SMD 0402")
    (property "Author" "Antmicro")
    (property "Current" "1A")
    (property "DNP" "DNP")
    (property "License" "Apache-2.0")
    (property "MPN" "ERJ2GE0R00X")
    (property "Manufacturer" "Panasonic")
    (property "Sheetfile" "sdi-mipi-bridge.kicad_sch")
    (property "Sheetname" "")
    (property "Tolerance" "")
    (property "Val" "0R")
    (property "ki_description" "0R resistor in 0402 package with unspecified tolerance")
    (attr exclude_from_pos_files)
    (fp_text reference "R42" (at -2.955 -0.4) (layer "F.SilkS")
        (effects (font (size 0.65 0.65) (thickness 0.15)) (justify right bottom))
    )
    (fp_text value "R_0R_0402" (at 0 1.4) (layer "F.Fab") hide
        (effects (font (size 0.7 0.7) (thickness 0.15)) (justify right bottom))
    )
    (fp_text user "License: Apache-2.0" (at -0.95 5.169) (layer "F.Fab") hide
        (effects (font (size 0.7 0.7) (thickness 0.15)) (justify right bottom))
    )
    (fp_text user "${REFERENCE}" (at -0.95 3.168) (layer "F.Fab") hide
        (effects (font (size 0.7 0.7) (thickness 0.15)) (justify right bottom))
    )
    (fp_text user "Author: Antmicro" (at -0.95 4.169) (layer "F.Fab") hide
        (effects (font (size 0.7 0.7) (thickness 0.15)) (justify right bottom))
    )
    (fp_rect (start -0.93 -0.47) (end 0.93 0.47)
      (stroke (width 0.05) (type solid)) (fill none) (layer "F.CrtYd"))
    (fp_rect (start -0.5 -0.25) (end 0.5 0.25)
      (stroke (width 0.15) (type solid)) (fill none) (layer "F.Fab"))
    (pad "1" smd roundrect (at -0.485 0 180) (size 0.59 0.64) (layers "F.Cu" "F.Paste" "F.Mask") (roundrect_rratio 0.25)
      (net 80 "/SCL2") (pintype "passive"))
    (pad "2" smd roundrect (at 0.485 0 180) (size 0.59 0.64) (layers "F.Cu" "F.Paste" "F.Mask") (roundrect_rratio 0.25)
      (net 99 "/SPI_SS(SCL)") (pintype "passive"))
  )
)
